FILE_TYPE = MULTI_PHYS_TABLE;

PART 'CONN9_GSB3111315HR'

{========================================================================================}
:VALUE                | PART_TYPE | MATERIAL | PART_NUMBER    = STANDARD        | LIFECYCLE      | PART_NUMBER   | JEDEC_TYPE | DESCRIPTION                            | MANUFTR | MANUF_PN       | RD_CMPLS_LVL | CMPLS_LVL | CLASS | DIP_SMD | FROM_PJ      | DATA                   | FP_ECN | EE_CHECK_LIST | CREATOR | CREATEDAY  | PSL | STATUS | ESD_CDM | ESD_HBM | ESD_MM | MSD | PIN_LENGTH_LONG_PIN | PIN_LENGTH_SHORT_PIN ;
{========================================================================================}
 'CONN9_GSB3111315HR' | 'THLF'    | 'IO'     | 'DFHS09FR401'(!) = ''               | ''               | 'DFHS09FR401' |'USB1XBH'| 'CONN DIP USB3.0 9P 2R FR(P2.0,H7.74)' | 'APL'   | 'GSB3111315HR' | 'EP(V1)'     | 'EP(V1)'  | 'IO'  | 'DIP'   | 'S5B-YU-LIN' | 'APL_GSB3111315HR.pdf' | ''     | ''            | ''      | '20220819' | ''  | ''     | ''      | ''      | ''     | ''  | '136 MILS'          | '105 MILS'          
 'CONN9_GSB3111315HR' | 'THLF'    | 'EMPTY'  | 'DFHS09FR401'(!) = ''               | ''               | 'DFHS09FR401' |'USB1XBH'| 'CONN DIP USB3.0 9P 2R FR(P2.0,H7.74)' | 'APL'   | 'GSB3111315HR' | 'EP(V1)'     | 'EP(V1)'  | 'IO'  | 'DIP'   | 'S5B-YU-LIN' | 'APL_GSB3111315HR.pdf' | ''     | ''            | ''      | '20220819' | ''  | ''     | ''      | ''      | ''     | ''  | '136 MILS'          | '105 MILS'          

END_PART

END.

